(kicad_pcb
	(version 20241229)
	(generator "pcbnew")
	(generator_version "9.0")
	(general
		(thickness 1.62)
		(legacy_teardrops no)
	)
	(paper "A4")
	(title_block
		(title "OCuLink to 10GbE adapter")
		(date "2026-02-23")
		(rev "1.1.0")
		(company "Antmicro Ltd")
		(comment 1 "www.antmicro.com")
		(comment 9 "footprints 24-29 of 510")
	)
	(layers
		(0 "F.Cu" signal)
		(4 "In1.Cu" signal)
		(6 "In2.Cu" signal)
		(8 "In3.Cu" signal)
		(10 "In4.Cu" signal)
		(12 "In5.Cu" signal)
		(14 "In6.Cu" signal)
		(2 "B.Cu" signal)
		(9 "F.Adhes" user "F.Adhesive")
		(11 "B.Adhes" user "B.Adhesive")
		(13 "F.Paste" user)
		(15 "B.Paste" user)
		(5 "F.SilkS" user "F.Silkscreen")
		(7 "B.SilkS" user "B.Silkscreen")
		(1 "F.Mask" user)
		(3 "B.Mask" user)
		(17 "Dwgs.User" user "User.Drawings")
		(19 "Cmts.User" user "User.Comments")
		(21 "Eco1.User" user "User.Eco1")
		(23 "Eco2.User" user "User.Eco2")
		(25 "Edge.Cuts" user)
		(27 "Margin" user)
		(31 "F.CrtYd" user "F.Courtyard")
		(29 "B.CrtYd" user "B.Courtyard")
		(35 "F.Fab" user)
		(33 "B.Fab" user)
	)
	(footprint "antmicro-footprints:R_0402_1005Metric"
		(layer "F.Cu")
		(at 54.099998 100.55 -90)
		(descr "Resistor SMD 0402")
		(tags "resistor SMD 0402")
		(property "Reference" "R18"
			(at -1.09 3.029998 90)
			(layer "F.SilkS")
			(effects
				(font
					(size 0.7 0.7)
					(thickness 0.15)
				)
				(justify right top)
			)
		)
		(property "Value" "R_30k_0402"
			(at -1.011843 1.772046 90)
			(layer "F.Fab")
			(hide yes)
			(effects
				(font
					(size 0.7 0.7)
					(thickness 0.15)
				)
				(justify right top)
			)
		)
		(property "Datasheet" "https://www.bourns.com/docs/product-datasheets/cr.pdf"
			(at 0 0 90)
			(layer "F.Fab")
			(hide yes)
			(effects
				(font
					(size 1.27 1.27)
					(thickness 0.15)
				)
			)
		)
		(property "Description" "SMD Chip Resistor, 30 kohm, ± 1%, 63 mW, 0402 [1005 Metric], Thick Film, General Purpose"
			(at 0 0 90)
			(layer "F.Fab")
			(hide yes)
			(effects
				(font
					(size 1.27 1.27)
					(thickness 0.15)
				)
			)
		)
		(property "MPN" "CR0402-FX-3002GLF"
			(at 0 0 270)
			(unlocked yes)
			(layer "F.Fab")
			(hide yes)
			(effects
				(font
					(size 1 1)
					(thickness 0.15)
				)
			)
		)
		(property "Manufacturer" "Bourns"
			(at 0 0 270)
			(unlocked yes)
			(layer "F.Fab")
			(hide yes)
			(effects
				(font
					(size 1 1)
					(thickness 0.15)
				)
			)
		)
		(property "License" "Apache-2.0"
			(at 0 0 270)
			(unlocked yes)
			(layer "F.Fab")
			(hide yes)
			(effects
				(font
					(size 1 1)
					(thickness 0.15)
				)
			)
		)
		(property "Author" "Antmicro"
			(at 0 0 270)
			(unlocked yes)
			(layer "F.Fab")
			(hide yes)
			(effects
				(font
					(size 1 1)
					(thickness 0.15)
				)
			)
		)
		(property "Val" "30k"
			(at 0 0 270)
			(unlocked yes)
			(layer "F.Fab")
			(hide yes)
			(effects
				(font
					(size 1 1)
					(thickness 0.15)
				)
			)
		)
		(property "Tolerance" "1%"
			(at 0 0 270)
			(unlocked yes)
			(layer "F.Fab")
			(hide yes)
			(effects
				(font
					(size 1 1)
					(thickness 0.15)
				)
			)
		)
		(sheetname "/Power/")
		(sheetfile "power.kicad_sch")
		(attr smd)
		(fp_rect
			(start -0.925 -0.47)
			(end 0.925 0.47)
			(stroke
				(width 0.05)
				(type default)
			)
			(fill no)
			(layer "F.CrtYd")
		)
		(fp_rect
			(start -0.5 -0.25)
			(end 0.5 0.25)
			(stroke
				(width 0.15)
				(type solid)
			)
			(fill no)
			(layer "F.Fab")
		)
		(pad "1" smd roundrect
			(at -0.48 0 270)
			(size 0.59 0.64)
			(layers "F.Cu" "F.Mask" "F.Paste")
			(roundrect_rratio 0.25)
			(net 28 "GND")
			(pintype "passive")
		)
		(pad "2" smd roundrect
			(at 0.48 0 270)
			(size 0.59 0.64)
			(layers "F.Cu" "F.Mask" "F.Paste")
			(roundrect_rratio 0.25)
			(net 330 "/Power/1V88_FB")
			(pintype "passive")
		)
	)
	(footprint "antmicro-footprints:L_Bourns-SRP2512A"
		(layer "F.Cu")
		(at 70.1 100.95)
		(property "Reference" "L9"
			(at -2.92 1.71 180)
			(layer "F.SilkS")
			(effects
				(font
					(size 0.7 0.7)
					(thickness 0.15)
				)
				(justify left bottom)
			)
		)
		(property "Value" "L_4u7_1.55A_Bourns-SRP2512A"
			(at 0 2.25 180)
			(layer "F.Fab")
			(hide yes)
			(effects
				(font
					(size 0.7 0.7)
					(thickness 0.15)
				)
				(justify left bottom)
			)
		)
		(property "Datasheet" "https://www.bourns.com/docs/Product-Datasheets/srp2512a.pdf"
			(at 0 0 0)
			(layer "F.Fab")
			(hide yes)
			(effects
				(font
					(size 1.27 1.27)
					(thickness 0.15)
				)
			)
		)
		(property "Description" "4.7 µH Shielded Drum Core, Wirewound Inductor 1.55 A 235mOhm Max 1008 (2520 Metric)"
			(at 0 0 0)
			(layer "F.Fab")
			(hide yes)
			(effects
				(font
					(size 1.27 1.27)
					(thickness 0.15)
				)
			)
		)
		(property "Val" "4u7/1.55A"
			(at 0 0 0)
			(unlocked yes)
			(layer "F.Fab")
			(hide yes)
			(effects
				(font
					(size 1 1)
					(thickness 0.15)
				)
			)
		)
		(property "Manufacturer" "Bourns"
			(at 0 0 0)
			(unlocked yes)
			(layer "F.Fab")
			(hide yes)
			(effects
				(font
					(size 1 1)
					(thickness 0.15)
				)
			)
		)
		(property "MPN" "SRP2512A-4R7M"
			(at 0 0 0)
			(unlocked yes)
			(layer "F.Fab")
			(hide yes)
			(effects
				(font
					(size 1 1)
					(thickness 0.15)
				)
			)
		)
		(property "ISat" "1.9 A"
			(at 0 0 0)
			(unlocked yes)
			(layer "F.Fab")
			(hide yes)
			(effects
				(font
					(size 1 1)
					(thickness 0.15)
				)
			)
		)
		(property "IMax" "1.55 A"
			(at 0 0 0)
			(unlocked yes)
			(layer "F.Fab")
			(hide yes)
			(effects
				(font
					(size 1 1)
					(thickness 0.15)
				)
			)
		)
		(property "Size" "2.5x2.0"
			(at 0 0 0)
			(unlocked yes)
			(layer "F.Fab")
			(hide yes)
			(effects
				(font
					(size 1 1)
					(thickness 0.15)
				)
			)
		)
		(property "Author" "Antmicro"
			(at 0 0 0)
			(unlocked yes)
			(layer "F.Fab")
			(hide yes)
			(effects
				(font
					(size 1 1)
					(thickness 0.15)
				)
			)
		)
		(property "License" "Apache-2.0"
			(at 0 0 0)
			(unlocked yes)
			(layer "F.Fab")
			(hide yes)
			(effects
				(font
					(size 1 1)
					(thickness 0.15)
				)
			)
		)
		(sheetname "/X710-AT2 power/")
		(sheetfile "x710-at2-power.kicad_sch")
		(attr smd)
		(fp_line
			(start -0.351 1)
			(end 0.349 1)
			(stroke
				(width 0.15)
				(type solid)
			)
			(layer "F.SilkS")
		)
		(fp_line
			(start -0.35 -1)
			(end 0.35 -1)
			(stroke
				(width 0.15)
				(type solid)
			)
			(layer "F.SilkS")
		)
		(fp_rect
			(start -1.65 -1.3)
			(end 1.65 1.3)
			(stroke
				(width 0.05)
				(type solid)
			)
			(fill no)
			(layer "F.CrtYd")
		)
		(pad "1" smd roundrect
			(at -1 0 90)
			(size 2 0.8)
			(layers "F.Cu" "F.Mask" "F.Paste")
			(roundrect_rratio 0.1)
			(net 302 "+1V0")
			(pintype "passive")
		)
		(pad "2" smd roundrect
			(at 1 0 90)
			(size 2 0.8)
			(layers "F.Cu" "F.Mask" "F.Paste")
			(roundrect_rratio 0.1)
			(net 12 "XFI_VDD")
			(pintype "passive")
		)
	)
	(footprint "antmicro-footprints:MP_Pad6mm_Drill3.2mm"
		(layer "F.Cu")
		(at 113 134.68)
		(property "Reference" "MP2"
			(at -1.1 -3.48 0)
			(layer "F.SilkS")
			(hide yes)
			(effects
				(font
					(size 0.7 0.7)
					(thickness 0.15)
				)
				(justify left bottom)
			)
		)
		(property "Value" "MP_Pad6mm_Drill3.2mm"
			(at 0 3.9 0)
			(layer "F.Fab")
			(hide yes)
			(effects
				(font
					(size 0.7 0.7)
					(thickness 0.15)
				)
				(justify left bottom)
			)
		)
		(property "Description" "Mechanical part"
			(at 0 0 0)
			(layer "F.Fab")
			(hide yes)
			(effects
				(font
					(size 1.27 1.27)
					(thickness 0.15)
				)
			)
		)
		(property "Author" "Antmicro"
			(at 0 0 0)
			(unlocked yes)
			(layer "F.Fab")
			(hide yes)
			(effects
				(font
					(size 1 1)
					(thickness 0.15)
				)
			)
		)
		(property "License" "Apache-2.0"
			(at 0 0 0)
			(unlocked yes)
			(layer "F.Fab")
			(hide yes)
			(effects
				(font
					(size 1 1)
					(thickness 0.15)
				)
			)
		)
		(sheetname "/")
		(sheetfile "oculink-to-10gbe-adapter.kicad_sch")
		(attr exclude_from_pos_files exclude_from_bom)
		(fp_circle
			(center 0 0)
			(end 3.25 0)
			(stroke
				(width 0.05)
				(type default)
			)
			(fill no)
			(layer "F.CrtYd")
		)
		(pad "1" thru_hole circle
			(at 0 0)
			(size 6 6)
			(drill 3.2)
			(layers "*.Cu" "*.Mask")
			(remove_unused_layers no)
			(net 28 "GND")
			(pintype "passive")
		)
	)
	(footprint "antmicro-footprints:R_0402_1005Metric"
		(layer "F.Cu")
		(at 57.85 78 90)
		(descr "Resistor SMD 0402")
		(tags "resistor SMD 0402")
		(property "Reference" "R33"
			(at -1.06 1.38 90)
			(layer "F.SilkS")
			(effects
				(font
					(size 0.7 0.7)
					(thickness 0.15)
				)
				(justify left bottom)
			)
		)
		(property "Value" "R_0R_0402"
			(at -1.011843 1.772046 90)
			(layer "F.Fab")
			(hide yes)
			(effects
				(font
					(size 0.7 0.7)
					(thickness 0.15)
				)
				(justify left bottom)
			)
		)
		(property "Datasheet" "https://industrial.panasonic.com/cdbs/www-data/pdf/RDA0000/AOA0000C301.pdf"
			(at 0 0 90)
			(layer "F.Fab")
			(hide yes)
			(effects
				(font
					(size 1.27 1.27)
					(thickness 0.15)
				)
			)
		)
		(property "Description" "SMD Chip Resistor, Jumper, 0 ohm, 100 mW, 0402 [1005 Metric], Thick Film, General Purpose"
			(at 0 0 90)
			(layer "F.Fab")
			(hide yes)
			(effects
				(font
					(size 1.27 1.27)
					(thickness 0.15)
				)
			)
		)
		(property "MPN" "ERJ2GE0R00X"
			(at 0 0 90)
			(unlocked yes)
			(layer "F.Fab")
			(hide yes)
			(effects
				(font
					(size 1 1)
					(thickness 0.15)
				)
			)
		)
		(property "Manufacturer" "Panasonic"
			(at 0 0 90)
			(unlocked yes)
			(layer "F.Fab")
			(hide yes)
			(effects
				(font
					(size 1 1)
					(thickness 0.15)
				)
			)
		)
		(property "License" "Apache-2.0"
			(at 0 0 90)
			(unlocked yes)
			(layer "F.Fab")
			(hide yes)
			(effects
				(font
					(size 1 1)
					(thickness 0.15)
				)
			)
		)
		(property "Author" "Antmicro"
			(at 0 0 90)
			(unlocked yes)
			(layer "F.Fab")
			(hide yes)
			(effects
				(font
					(size 1 1)
					(thickness 0.15)
				)
			)
		)
		(property "Val" "0R"
			(at 0 0 90)
			(unlocked yes)
			(layer "F.Fab")
			(hide yes)
			(effects
				(font
					(size 1 1)
					(thickness 0.15)
				)
			)
		)
		(property "Tolerance" "~"
			(at 0 0 90)
			(unlocked yes)
			(layer "F.Fab")
			(hide yes)
			(effects
				(font
					(size 1 1)
					(thickness 0.15)
				)
			)
		)
		(property "Current" "1A"
			(at 0 0 90)
			(unlocked yes)
			(layer "F.Fab")
			(hide yes)
			(effects
				(font
					(size 1 1)
					(thickness 0.15)
				)
			)
		)
		(sheetname "/Power/")
		(sheetfile "power.kicad_sch")
		(attr smd)
		(fp_rect
			(start -0.925 -0.47)
			(end 0.925 0.47)
			(stroke
				(width 0.05)
				(type default)
			)
			(fill no)
			(layer "F.CrtYd")
		)
		(fp_rect
			(start -0.5 -0.25)
			(end 0.5 0.25)
			(stroke
				(width 0.15)
				(type solid)
			)
			(fill no)
			(layer "F.Fab")
		)
		(pad "1" smd roundrect
			(at -0.48 0 90)
			(size 0.59 0.64)
			(layers "F.Cu" "F.Mask" "F.Paste")
			(roundrect_rratio 0.25)
			(net 378 "/Power/DVDD_PG")
			(pintype "passive")
		)
		(pad "2" smd roundrect
			(at 0.48 0 90)
			(size 0.59 0.64)
			(layers "F.Cu" "F.Mask" "F.Paste")
			(roundrect_rratio 0.25)
			(net 392 "/Power/ALL_RAILS_OK")
			(pintype "passive")
		)
	)
	(footprint "antmicro-footprints:C_0402_1005Metric"
		(layer "F.Cu")
		(at 56.399999 97.799999)
		(descr "Capacitor SMD 0402")
		(tags "capacitor SMD 0402")
		(property "Reference" "C38"
			(at -1.549999 1.210001 0)
			(layer "F.SilkS")
			(effects
				(font
					(size 0.7 0.7)
					(thickness 0.15)
				)
				(justify left bottom)
			)
		)
		(property "Value" "C_100n_0402"
			(at -1.022927 2.155213 0)
			(layer "F.Fab")
			(hide yes)
			(effects
				(font
					(size 0.7 0.7)
					(thickness 0.15)
				)
				(justify left bottom)
			)
		)
		(property "Datasheet" "https://www.murata.com/products/productdetail?partno=GRM155R61H104KE14%23"
			(at 0 0 0)
			(layer "F.Fab")
			(hide yes)
			(effects
				(font
					(size 1.27 1.27)
					(thickness 0.15)
				)
			)
		)
		(property "Description" "SMD Multilayer Ceramic Capacitor, 0.1 µF, 50 V, 0402 [1005 Metric], ± 10%, X5R, GRM Series"
			(at 0 0 0)
			(layer "F.Fab")
			(hide yes)
			(effects
				(font
					(size 1.27 1.27)
					(thickness 0.15)
				)
			)
		)
		(property "MPN" "GRM155R61H104KE14D"
			(at 0 0 0)
			(unlocked yes)
			(layer "F.Fab")
			(hide yes)
			(effects
				(font
					(size 1 1)
					(thickness 0.15)
				)
			)
		)
		(property "Manufacturer" "Murata"
			(at 0 0 0)
			(unlocked yes)
			(layer "F.Fab")
			(hide yes)
			(effects
				(font
					(size 1 1)
					(thickness 0.15)
				)
			)
		)
		(property "License" "Apache-2.0"
			(at 0 0 0)
			(unlocked yes)
			(layer "F.Fab")
			(hide yes)
			(effects
				(font
					(size 1 1)
					(thickness 0.15)
				)
			)
		)
		(property "Author" "Antmicro"
			(at 0 0 0)
			(unlocked yes)
			(layer "F.Fab")
			(hide yes)
			(effects
				(font
					(size 1 1)
					(thickness 0.15)
				)
			)
		)
		(property "Val" "100n"
			(at 0 0 0)
			(unlocked yes)
			(layer "F.Fab")
			(hide yes)
			(effects
				(font
					(size 1 1)
					(thickness 0.15)
				)
			)
		)
		(property "Voltage" "50V"
			(at 0 0 0)
			(unlocked yes)
			(layer "F.Fab")
			(hide yes)
			(effects
				(font
					(size 1 1)
					(thickness 0.15)
				)
			)
		)
		(property "Dielectric" "X5R"
			(at 0 0 0)
			(unlocked yes)
			(layer "F.Fab")
			(hide yes)
			(effects
				(font
					(size 1 1)
					(thickness 0.15)
				)
			)
		)
		(sheetname "/Power/")
		(sheetfile "power.kicad_sch")
		(attr smd)
		(fp_rect
			(start -0.925 -0.47)
			(end 0.925 0.47)
			(stroke
				(width 0.05)
				(type default)
			)
			(fill no)
			(layer "F.CrtYd")
		)
		(fp_line
			(start -0.494 -0.25)
			(end 0.504 -0.25)
			(stroke
				(width 0.15)
				(type solid)
			)
			(layer "F.Fab")
		)
		(fp_line
			(start -0.494 0.248)
			(end -0.494 -0.25)
			(stroke
				(width 0.15)
				(type solid)
			)
			(layer "F.Fab")
		)
		(fp_line
			(start 0.504 -0.25)
			(end 0.504 0.248)
			(stroke
				(width 0.15)
				(type solid)
			)
			(layer "F.Fab")
		)
		(fp_line
			(start 0.504 0.248)
			(end -0.494 0.248)
			(stroke
				(width 0.15)
				(type solid)
			)
			(layer "F.Fab")
		)
		(pad "1" smd roundrect
			(at -0.48 0)
			(size 0.59 0.64)
			(layers "F.Cu" "F.Mask" "F.Paste")
			(roundrect_rratio 0.25)
			(net 325 "/Power/DVDD_BST")
			(pintype "passive")
		)
		(pad "2" smd roundrect
			(at 0.48 0)
			(size 0.59 0.64)
			(layers "F.Cu" "F.Mask" "F.Paste")
			(roundrect_rratio 0.25)
			(net 336 "/Power/DVDD_SW")
			(pintype "passive")
		)
	)
	(footprint "antmicro-footprints:C_0402_1005Metric"
		(layer "F.Cu")
		(at 109.15 102.05 90)
		(descr "Capacitor SMD 0402")
		(tags "capacitor SMD 0402")
		(property "Reference" "C209"
			(at -1.35 -0.65 90)
			(layer "F.SilkS")
			(effects
				(font
					(size 0.7 0.7)
					(thickness 0.15)
				)
				(justify left bottom)
			)
		)
		(property "Value" "C_1u_25V_0402"
			(at -1.022927 2.155213 90)
			(layer "F.Fab")
			(hide yes)
			(effects
				(font
					(size 0.7 0.7)
					(thickness 0.15)
				)
				(justify left bottom)
			)
		)
		(property "Datasheet" "https://www.murata.com/products/productdetail?partno=GRM155R61E105KE11%23"
			(at 0 0 90)
			(layer "F.Fab")
			(hide yes)
			(effects
				(font
					(size 1.27 1.27)
					(thickness 0.15)
				)
			)
		)
		(property "Description" "SMD Multilayer Ceramic Capacitor, 1 µF, 25 V, 0402 [1005 Metric], ± 10%, X5R, GRM Series"
			(at 0 0 90)
			(layer "F.Fab")
			(hide yes)
			(effects
				(font
					(size 1.27 1.27)
					(thickness 0.15)
				)
			)
		)
		(property "MPN" "GRM155R61E105KE11J"
			(at 0 0 90)
			(unlocked yes)
			(layer "F.Fab")
			(hide yes)
			(effects
				(font
					(size 1 1)
					(thickness 0.15)
				)
			)
		)
		(property "Manufacturer" "Murata"
			(at 0 0 90)
			(unlocked yes)
			(layer "F.Fab")
			(hide yes)
			(effects
				(font
					(size 1 1)
					(thickness 0.15)
				)
			)
		)
		(property "License" "Apache-2.0"
			(at 0 0 90)
			(unlocked yes)
			(layer "F.Fab")
			(hide yes)
			(effects
				(font
					(size 1 1)
					(thickness 0.15)
				)
			)
		)
		(property "Author" "Antmicro"
			(at 0 0 90)
			(unlocked yes)
			(layer "F.Fab")
			(hide yes)
			(effects
				(font
					(size 1 1)
					(thickness 0.15)
				)
			)
		)
		(property "Val" "1u"
			(at 0 0 90)
			(unlocked yes)
			(layer "F.Fab")
			(hide yes)
			(effects
				(font
					(size 1 1)
					(thickness 0.15)
				)
			)
		)
		(property "Voltage" "25V"
			(at 0 0 90)
			(unlocked yes)
			(layer "F.Fab")
			(hide yes)
			(effects
				(font
					(size 1 1)
					(thickness 0.15)
				)
			)
		)
		(property "Dielectric" "X5R"
			(at 0 0 90)
			(unlocked yes)
			(layer "F.Fab")
			(hide yes)
			(effects
				(font
					(size 1 1)
					(thickness 0.15)
				)
			)
		)
		(sheetname "/Fan controller/")
		(sheetfile "fan-controller.kicad_sch")
		(attr smd exclude_from_pos_files exclude_from_bom dnp)
		(fp_rect
			(start -0.925 -0.47)
			(end 0.925 0.47)
			(stroke
				(width 0.05)
				(type default)
			)
			(fill no)
			(layer "F.CrtYd")
		)
		(fp_line
			(start 0.504 -0.25)
			(end 0.504 0.248)
			(stroke
				(width 0.15)
				(type solid)
			)
			(layer "F.Fab")
		)
		(fp_line
			(start -0.494 -0.25)
			(end 0.504 -0.25)
			(stroke
				(width 0.15)
				(type solid)
			)
			(layer "F.Fab")
		)
		(fp_line
			(start 0.504 0.248)
			(end -0.494 0.248)
			(stroke
				(width 0.15)
				(type solid)
			)
			(layer "F.Fab")
		)
		(fp_line
			(start -0.494 0.248)
			(end -0.494 -0.25)
			(stroke
				(width 0.15)
				(type solid)
			)
			(layer "F.Fab")
		)
		(pad "1" smd roundrect
			(at -0.48 0 90)
			(size 0.59 0.64)
			(layers "F.Cu" "F.Mask" "F.Paste")
			(roundrect_rratio 0.25)
			(net 28 "GND")
			(pintype "passive")
		)
		(pad "2" smd roundrect
			(at 0.48 0 90)
			(size 0.59 0.64)
			(layers "F.Cu" "F.Mask" "F.Paste")
			(roundrect_rratio 0.25)
			(net 385 "/Fan controller/SENSE")
			(pintype "passive")
		)
	)
)
